(kicad_pcb
	(version 20241229)
	(generator "pcbnew")
	(generator_version "9.0")
	(general
		(thickness 1.599998)
		(legacy_teardrops no)
	)
	(paper "A4")
	(title_block
		(date "2023-02-12")
		(rev "1.1.5")
		(comment 9 "footprints 316-321 of 473")
	)
	(layers
		(0 "F.Cu" signal)
		(4 "In1.Cu" power "In1.GND")
		(6 "In2.Cu" signal)
		(8 "In3.Cu" power "In3.GND")
		(10 "In4.Cu" power "In4.VCC")
		(12 "In5.Cu" signal)
		(14 "In6.Cu" power "In6.VCC")
		(2 "B.Cu" signal)
		(9 "F.Adhes" user "F.Adhesive")
		(11 "B.Adhes" user "B.Adhesive")
		(13 "F.Paste" user)
		(15 "B.Paste" user)
		(5 "F.SilkS" user "F.Silkscreen")
		(7 "B.SilkS" user "B.Silkscreen")
		(1 "F.Mask" user)
		(3 "B.Mask" user)
		(17 "Dwgs.User" user "User.Drawings")
		(19 "Cmts.User" user "User.Comments")
		(21 "Eco1.User" user "User.Eco1")
		(23 "Eco2.User" user "User.Eco2")
		(25 "Edge.Cuts" user)
		(27 "Margin" user)
		(31 "F.CrtYd" user "F.Courtyard")
		(29 "B.CrtYd" user "B.Courtyard")
		(35 "F.Fab" user)
		(33 "B.Fab" user)
	)
	(footprint "antmicro-footprints:L_WE-MAIA-2512"
		(layer "F.Cu")
		(at 113.897806 84.774 180)
		(property "Reference" "L3"
			(at -1.5 -1.4 180)
			(layer "F.SilkS")
			(effects
				(font
					(size 0.7 0.7)
					(thickness 0.15)
				)
				(justify left bottom)
			)
		)
		(property "Value" "784383240047"
			(at 0 2.3 180)
			(layer "F.Fab")
			(effects
				(font
					(size 0.7 0.7)
					(thickness 0.15)
				)
				(justify left bottom)
			)
		)
		(property "Description" "Power Inductor (SMT), AEC-Q200, 470 nH, 3.4 A, Shielded, 6.25 A, WE-MAIA"
			(at 0 0 180)
			(layer "F.Fab")
			(hide yes)
			(effects
				(font
					(size 1.27 1.27)
					(thickness 0.15)
				)
			)
		)
		(property "Author" "Antmicro"
			(at 227.795612 169.548 0)
			(layer "F.Fab")
			(hide yes)
			(effects
				(font
					(size 1 1)
					(thickness 0.15)
				)
			)
		)
		(property "IMax" "3.4 A"
			(at 227.795612 169.548 0)
			(layer "F.Fab")
			(hide yes)
			(effects
				(font
					(size 1 1)
					(thickness 0.15)
				)
			)
		)
		(property "ISat" "6.25 A"
			(at 227.795612 169.548 0)
			(layer "F.Fab")
			(hide yes)
			(effects
				(font
					(size 1 1)
					(thickness 0.15)
				)
			)
		)
		(property "License" "Apache-2.0"
			(at 227.795612 169.548 0)
			(layer "F.Fab")
			(hide yes)
			(effects
				(font
					(size 1 1)
					(thickness 0.15)
				)
			)
		)
		(property "MPN" "784383240047"
			(at 227.795612 169.548 0)
			(layer "F.Fab")
			(hide yes)
			(effects
				(font
					(size 1 1)
					(thickness 0.15)
				)
			)
		)
		(property "Manufacturer" "Würth Elektronik"
			(at 227.795612 169.548 0)
			(layer "F.Fab")
			(hide yes)
			(effects
				(font
					(size 1 1)
					(thickness 0.15)
				)
			)
		)
		(property "Size" "2x2.5"
			(at 227.795612 169.548 0)
			(layer "F.Fab")
			(hide yes)
			(effects
				(font
					(size 1 1)
					(thickness 0.15)
				)
			)
		)
		(property "Val" "470n/3.4A"
			(at 227.795612 169.548 0)
			(layer "F.Fab")
			(hide yes)
			(effects
				(font
					(size 1 1)
					(thickness 0.15)
				)
			)
		)
		(sheetname "Supply")
		(sheetfile "supply.kicad_sch")
		(attr smd)
		(fp_line
			(start -0.325 1.125)
			(end 0.325 1.125)
			(stroke
				(width 0.15)
				(type solid)
			)
			(layer "F.SilkS")
		)
		(fp_line
			(start -0.325 -1.125)
			(end 0.325 -1.125)
			(stroke
				(width 0.15)
				(type solid)
			)
			(layer "F.SilkS")
		)
		(fp_rect
			(start -1.65 -1.4)
			(end 1.65 1.4)
			(stroke
				(width 0.05)
				(type solid)
			)
			(fill no)
			(layer "F.CrtYd")
		)
		(fp_rect
			(start -1.25 -1)
			(end 1.25 1)
			(stroke
				(width 0.15)
				(type solid)
			)
			(fill no)
			(layer "F.Fab")
		)
		(pad "1" smd roundrect
			(at -0.975 0 180)
			(size 0.85 2.3)
			(layers "F.Cu" "F.Mask" "F.Paste")
			(roundrect_rratio 0.1)
			(net 584 "/Supply/1V8_SW")
			(pintype "passive")
		)
		(pad "2" smd roundrect
			(at 0.975 0 180)
			(size 0.85 2.3)
			(layers "F.Cu" "F.Mask" "F.Paste")
			(roundrect_rratio 0.1)
			(net 583 "/Supply/1V8_REG")
			(pintype "passive")
		)
	)
	(footprint "antmicro-footprints:R_0805_2012Metric"
		(layer "F.Cu")
		(at 114.325 93.749)
		(property "Reference" "R117"
			(at 1.575 0.351 0)
			(layer "F.SilkS")
			(effects
				(font
					(size 0.7 0.7)
					(thickness 0.15)
				)
				(justify left bottom)
			)
		)
		(property "Value" "R_0R_0805"
			(at 0 1.8 0)
			(layer "F.Fab")
			(effects
				(font
					(size 0.7 0.7)
					(thickness 0.15)
				)
				(justify left bottom)
			)
		)
		(property "Description" "0R resistor in 0805 package with unspecified tolerance"
			(at 0 0 0)
			(layer "F.Fab")
			(hide yes)
			(effects
				(font
					(size 1.27 1.27)
					(thickness 0.15)
				)
			)
		)
		(property "Author" "Antmicro"
			(at 0 0 0)
			(layer "F.Fab")
			(hide yes)
			(effects
				(font
					(size 1 1)
					(thickness 0.15)
				)
			)
		)
		(property "Current" "2.5A"
			(at 0 0 0)
			(layer "F.Fab")
			(hide yes)
			(effects
				(font
					(size 1 1)
					(thickness 0.15)
				)
			)
		)
		(property "License" "Apache-2.0"
			(at 0 0 0)
			(layer "F.Fab")
			(hide yes)
			(effects
				(font
					(size 1 1)
					(thickness 0.15)
				)
			)
		)
		(property "MPN" "CRCW08050000Z0EA"
			(at 0 0 0)
			(layer "F.Fab")
			(hide yes)
			(effects
				(font
					(size 1 1)
					(thickness 0.15)
				)
			)
		)
		(property "Manufacturer" "Vishay"
			(at 0 0 0)
			(layer "F.Fab")
			(hide yes)
			(effects
				(font
					(size 1 1)
					(thickness 0.15)
				)
			)
		)
		(property "Tolerance" ""
			(at 0 0 0)
			(layer "F.Fab")
			(hide yes)
			(effects
				(font
					(size 1 1)
					(thickness 0.15)
				)
			)
		)
		(property "Val" "0R"
			(at 0 0 0)
			(layer "F.Fab")
			(hide yes)
			(effects
				(font
					(size 1 1)
					(thickness 0.15)
				)
			)
		)
		(sheetname "Supply")
		(sheetfile "supply.kicad_sch")
		(attr smd)
		(fp_line
			(start -0.32 0.699)
			(end 0.28 0.699)
			(stroke
				(width 0.15)
				(type solid)
			)
			(layer "F.SilkS")
		)
		(fp_line
			(start -0.3 -0.701)
			(end 0.298 -0.701)
			(stroke
				(width 0.15)
				(type solid)
			)
			(layer "F.SilkS")
		)
		(fp_rect
			(start -1.75 -0.85)
			(end 1.75 0.85)
			(stroke
				(width 0.05)
				(type solid)
			)
			(fill no)
			(layer "F.CrtYd")
		)
		(fp_line
			(start -0.951 -0.682)
			(end 0.949 -0.682)
			(stroke
				(width 0.15)
				(type solid)
			)
			(layer "F.Fab")
		)
		(fp_line
			(start -0.951 -0.677)
			(end -0.951 0.675)
			(stroke
				(width 0.15)
				(type solid)
			)
			(layer "F.Fab")
		)
		(fp_line
			(start -0.951 0.68)
			(end 0.949 0.68)
			(stroke
				(width 0.15)
				(type solid)
			)
			(layer "F.Fab")
		)
		(fp_line
			(start 0.949 -0.677)
			(end 0.949 0.675)
			(stroke
				(width 0.15)
				(type solid)
			)
			(layer "F.Fab")
		)
		(pad "1" smd roundrect
			(at -1.1 -0.001)
			(size 1 1.4)
			(layers "F.Cu" "F.Mask" "F.Paste")
			(roundrect_rratio 0.15)
			(net 576 "/Supply/3V3_REG")
			(pintype "passive")
		)
		(pad "2" smd roundrect
			(at 1.1 -0.001)
			(size 1 1.4)
			(layers "F.Cu" "F.Mask" "F.Paste")
			(roundrect_rratio 0.15)
			(net 459 "3V3_SYS")
			(pintype "passive")
		)
	)
	(footprint "antmicro-footprints:R_0402_1005Metric"
		(layer "F.Cu")
		(at 117.697806 90.074 180)
		(descr "Resistor SMD 0402")
		(tags "resistor SMD 0402")
		(property "Reference" "R118"
			(at 0.897806 3.574 180)
			(layer "F.SilkS")
			(effects
				(font
					(size 0.7 0.7)
					(thickness 0.15)
				)
				(justify left bottom)
			)
		)
		(property "Value" "R_100k_0402"
			(at 0 1.4 180)
			(layer "F.Fab")
			(effects
				(font
					(size 0.7 0.7)
					(thickness 0.15)
				)
				(justify left bottom)
			)
		)
		(property "Description" "100k resistor in 0402 package with 1% tolerance"
			(at 0 0 180)
			(layer "F.Fab")
			(hide yes)
			(effects
				(font
					(size 1.27 1.27)
					(thickness 0.15)
				)
			)
		)
		(property "Author" "Antmicro"
			(at 235.395612 180.148 0)
			(layer "F.Fab")
			(hide yes)
			(effects
				(font
					(size 1 1)
					(thickness 0.15)
				)
			)
		)
		(property "License" "Apache-2.0"
			(at 235.395612 180.148 0)
			(layer "F.Fab")
			(hide yes)
			(effects
				(font
					(size 1 1)
					(thickness 0.15)
				)
			)
		)
		(property "MPN" "CR0402-FX-1003GLF"
			(at 235.395612 180.148 0)
			(layer "F.Fab")
			(hide yes)
			(effects
				(font
					(size 1 1)
					(thickness 0.15)
				)
			)
		)
		(property "Manufacturer" "Bourns"
			(at 235.395612 180.148 0)
			(layer "F.Fab")
			(hide yes)
			(effects
				(font
					(size 1 1)
					(thickness 0.15)
				)
			)
		)
		(property "Tolerance" "1%"
			(at 235.395612 180.148 0)
			(layer "F.Fab")
			(hide yes)
			(effects
				(font
					(size 1 1)
					(thickness 0.15)
				)
			)
		)
		(property "Val" "100k"
			(at 235.395612 180.148 0)
			(layer "F.Fab")
			(hide yes)
			(effects
				(font
					(size 1 1)
					(thickness 0.15)
				)
			)
		)
		(sheetname "Supply")
		(sheetfile "supply.kicad_sch")
		(attr smd)
		(fp_rect
			(start -0.93 -0.47)
			(end 0.93 0.47)
			(stroke
				(width 0.05)
				(type solid)
			)
			(fill no)
			(layer "F.CrtYd")
		)
		(fp_rect
			(start -0.5 -0.25)
			(end 0.5 0.25)
			(stroke
				(width 0.15)
				(type solid)
			)
			(fill no)
			(layer "F.Fab")
		)
		(pad "1" smd roundrect
			(at -0.485 0 180)
			(size 0.59 0.64)
			(layers "F.Cu" "F.Mask" "F.Paste")
			(roundrect_rratio 0.25)
			(net 469 "/Supply/VCC_AUX_EN")
			(pintype "passive")
		)
		(pad "2" smd roundrect
			(at 0.485 0 180)
			(size 0.59 0.64)
			(layers "F.Cu" "F.Mask" "F.Paste")
			(roundrect_rratio 0.25)
			(net 594 "/Supply/1V8_EN")
			(pintype "passive")
		)
	)
	(footprint "antmicro-footprints:C_0402_1005Metric"
		(layer "F.Cu")
		(at 111.362806 87.974 180)
		(descr "Capacitor SMD 0402")
		(tags "capacitor SMD 0402")
		(property "Reference" "C163"
			(at 3.662806 -0.326 180)
			(layer "F.SilkS")
			(effects
				(font
					(size 0.7 0.7)
					(thickness 0.15)
				)
				(justify left bottom)
			)
		)
		(property "Value" "C_1u_0402"
			(at 0 1.4 180)
			(layer "F.Fab")
			(effects
				(font
					(size 0.7 0.7)
					(thickness 0.15)
				)
				(justify left bottom)
			)
		)
		(property "Description" " "
			(at 0 0 180)
			(layer "F.Fab")
			(hide yes)
			(effects
				(font
					(size 1.27 1.27)
					(thickness 0.15)
				)
			)
		)
		(property "Author" "Antmicro"
			(at 222.725612 175.948 0)
			(layer "F.Fab")
			(hide yes)
			(effects
				(font
					(size 1 1)
					(thickness 0.15)
				)
			)
		)
		(property "Dielectric" ""
			(at 222.725612 175.948 0)
			(layer "F.Fab")
			(hide yes)
			(effects
				(font
					(size 1 1)
					(thickness 0.15)
				)
			)
		)
		(property "License" "Apache-2.0"
			(at 222.725612 175.948 0)
			(layer "F.Fab")
			(hide yes)
			(effects
				(font
					(size 1 1)
					(thickness 0.15)
				)
			)
		)
		(property "MPN" "C1005X6S1A105K050BC"
			(at 222.725612 175.948 0)
			(layer "F.Fab")
			(hide yes)
			(effects
				(font
					(size 1 1)
					(thickness 0.15)
				)
			)
		)
		(property "Manufacturer" "TDK"
			(at 222.725612 175.948 0)
			(layer "F.Fab")
			(hide yes)
			(effects
				(font
					(size 1 1)
					(thickness 0.15)
				)
			)
		)
		(property "Val" "1u"
			(at 222.725612 175.948 0)
			(layer "F.Fab")
			(hide yes)
			(effects
				(font
					(size 1 1)
					(thickness 0.15)
				)
			)
		)
		(property "Voltage" ""
			(at 222.725612 175.948 0)
			(layer "F.Fab")
			(hide yes)
			(effects
				(font
					(size 1 1)
					(thickness 0.15)
				)
			)
		)
		(sheetname "Supply")
		(sheetfile "supply.kicad_sch")
		(attr smd)
		(fp_rect
			(start -0.94 -0.47)
			(end 0.94 0.47)
			(stroke
				(width 0.05)
				(type solid)
			)
			(fill no)
			(layer "F.CrtYd")
		)
		(fp_rect
			(start -0.499 -0.249)
			(end 0.499 0.249)
			(stroke
				(width 0.15)
				(type solid)
			)
			(fill no)
			(layer "F.Fab")
		)
		(pad "1" smd roundrect
			(at -0.484 0 180)
			(size 0.59 0.64)
			(layers "F.Cu" "F.Mask" "F.Paste")
			(roundrect_rratio 0.25)
			(net 595 "/Supply/1V8_VCC_INT")
			(pintype "passive")
		)
		(pad "2" smd roundrect
			(at 0.484 0 180)
			(size 0.59 0.64)
			(layers "F.Cu" "F.Mask" "F.Paste")
			(roundrect_rratio 0.25)
			(net 5 "GND")
			(pintype "passive")
		)
	)
	(footprint "antmicro-footprints:R_0402_1005Metric"
		(layer "F.Cu")
		(at 129.9825 101.549 180)
		(descr "Resistor SMD 0402")
		(tags "resistor SMD 0402")
		(property "Reference" "R130"
			(at -0.7175 -0.451 180)
			(layer "F.SilkS")
			(effects
				(font
					(size 0.7 0.7)
					(thickness 0.15)
				)
				(justify left bottom)
			)
		)
		(property "Value" "R_100k_0402"
			(at 0 1.4 180)
			(layer "F.Fab")
			(effects
				(font
					(size 0.7 0.7)
					(thickness 0.15)
				)
				(justify left bottom)
			)
		)
		(property "Description" "100k resistor in 0402 package with 1% tolerance"
			(at 0 0 180)
			(layer "F.Fab")
			(hide yes)
			(effects
				(font
					(size 1.27 1.27)
					(thickness 0.15)
				)
			)
		)
		(property "Author" "Antmicro"
			(at 259.965 203.098 0)
			(layer "F.Fab")
			(hide yes)
			(effects
				(font
					(size 1 1)
					(thickness 0.15)
				)
			)
		)
		(property "License" "Apache-2.0"
			(at 259.965 203.098 0)
			(layer "F.Fab")
			(hide yes)
			(effects
				(font
					(size 1 1)
					(thickness 0.15)
				)
			)
		)
		(property "MPN" "CR0402-FX-1003GLF"
			(at 259.965 203.098 0)
			(layer "F.Fab")
			(hide yes)
			(effects
				(font
					(size 1 1)
					(thickness 0.15)
				)
			)
		)
		(property "Manufacturer" "Bourns"
			(at 259.965 203.098 0)
			(layer "F.Fab")
			(hide yes)
			(effects
				(font
					(size 1 1)
					(thickness 0.15)
				)
			)
		)
		(property "Tolerance" "1%"
			(at 259.965 203.098 0)
			(layer "F.Fab")
			(hide yes)
			(effects
				(font
					(size 1 1)
					(thickness 0.15)
				)
			)
		)
		(property "Val" "100k"
			(at 259.965 203.098 0)
			(layer "F.Fab")
			(hide yes)
			(effects
				(font
					(size 1 1)
					(thickness 0.15)
				)
			)
		)
		(sheetname "Supply")
		(sheetfile "supply.kicad_sch")
		(attr smd)
		(fp_rect
			(start -0.93 -0.47)
			(end 0.93 0.47)
			(stroke
				(width 0.05)
				(type solid)
			)
			(fill no)
			(layer "F.CrtYd")
		)
		(fp_rect
			(start -0.5 -0.25)
			(end 0.5 0.25)
			(stroke
				(width 0.15)
				(type solid)
			)
			(fill no)
			(layer "F.Fab")
		)
		(pad "1" smd roundrect
			(at -0.485 0 180)
			(size 0.59 0.64)
			(layers "F.Cu" "F.Mask" "F.Paste")
			(roundrect_rratio 0.25)
			(net 468 "/Supply/VCC_INT_EN")
			(pintype "passive")
		)
		(pad "2" smd roundrect
			(at 0.485 0 180)
			(size 0.59 0.64)
			(layers "F.Cu" "F.Mask" "F.Paste")
			(roundrect_rratio 0.25)
			(net 592 "/Supply/1V0_EN")
			(pintype "passive")
		)
	)
	(footprint "antmicro-footprints:R_0402_1005Metric"
		(layer "F.Cu")
		(at 186 118.185 90)
		(descr "Resistor SMD 0402")
		(tags "resistor SMD 0402")
		(property "Reference" "R151"
			(at -3.615 0.436828 90)
			(layer "F.SilkS")
			(effects
				(font
					(size 0.7 0.7)
					(thickness 0.15)
				)
				(justify left bottom)
			)
		)
		(property "Value" "R_0R_0402"
			(at 0 1.4 90)
			(layer "F.Fab")
			(effects
				(font
					(size 0.7 0.7)
					(thickness 0.15)
				)
				(justify left bottom)
			)
		)
		(property "Description" "0R resistor in 0402 package with unspecified tolerance"
			(at 0 0 90)
			(layer "F.Fab")
			(hide yes)
			(effects
				(font
					(size 1.27 1.27)
					(thickness 0.15)
				)
			)
		)
		(property "Author" "Antmicro"
			(at 304.185 -67.815 0)
			(layer "F.Fab")
			(hide yes)
			(effects
				(font
					(size 1 1)
					(thickness 0.15)
				)
			)
		)
		(property "Current" "1A"
			(at 304.185 -67.815 0)
			(layer "F.Fab")
			(hide yes)
			(effects
				(font
					(size 1 1)
					(thickness 0.15)
				)
			)
		)
		(property "License" "Apache-2.0"
			(at 304.185 -67.815 0)
			(layer "F.Fab")
			(hide yes)
			(effects
				(font
					(size 1 1)
					(thickness 0.15)
				)
			)
		)
		(property "MPN" "ERJ2GE0R00X"
			(at 304.185 -67.815 0)
			(layer "F.Fab")
			(hide yes)
			(effects
				(font
					(size 1 1)
					(thickness 0.15)
				)
			)
		)
		(property "Manufacturer" "Panasonic"
			(at 304.185 -67.815 0)
			(layer "F.Fab")
			(hide yes)
			(effects
				(font
					(size 1 1)
					(thickness 0.15)
				)
			)
		)
		(property "Tolerance" ""
			(at 304.185 -67.815 0)
			(layer "F.Fab")
			(hide yes)
			(effects
				(font
					(size 1 1)
					(thickness 0.15)
				)
			)
		)
		(property "Val" "0R"
			(at 304.185 -67.815 0)
			(layer "F.Fab")
			(hide yes)
			(effects
				(font
					(size 1 1)
					(thickness 0.15)
				)
			)
		)
		(sheetname "Supply")
		(sheetfile "supply.kicad_sch")
		(attr smd)
		(fp_rect
			(start -0.93 -0.47)
			(end 0.93 0.47)
			(stroke
				(width 0.05)
				(type solid)
			)
			(fill no)
			(layer "F.CrtYd")
		)
		(fp_rect
			(start -0.5 -0.25)
			(end 0.5 0.25)
			(stroke
				(width 0.15)
				(type solid)
			)
			(fill no)
			(layer "F.Fab")
		)
		(pad "1" smd roundrect
			(at -0.485 0 90)
			(size 0.59 0.64)
			(layers "F.Cu" "F.Mask" "F.Paste")
			(roundrect_rratio 0.25)
			(net 5 "GND")
			(pintype "passive")
		)
		(pad "2" smd roundrect
			(at 0.485 0 90)
			(size 0.59 0.64)
			(layers "F.Cu" "F.Mask" "F.Paste")
			(roundrect_rratio 0.25)
			(net 623 "/Supply/1V2_MODE")
			(pintype "passive")
		)
	)
)
